(kicad_pcb
	(version 20260206)
	(generator "pcbnew")
	(generator_version "10.0")
	(general
		(thickness 1.6)
		(legacy_teardrops no)
	)
	(paper "A4")
	(title_block
		(title "Wiwynn_Tioga_Pass_MB.brd")
		(comment 1 "Tioga Pass / footprints 3386-3391 of 4770")
	)
	(layers
		(0 "F.Cu" signal "TOP")
		(4 "In1.Cu" signal "L2GND")
		(6 "In2.Cu" signal "L3")
		(8 "In3.Cu" signal "L4GND")
		(10 "In4.Cu" signal "L5")
		(12 "In5.Cu" signal "L6GND")
		(14 "In6.Cu" signal "L7VCC")
		(16 "In7.Cu" signal "L8VCC")
		(18 "In8.Cu" signal "L9GND")
		(20 "In9.Cu" signal "L10")
		(22 "In10.Cu" signal "L11GND")
		(24 "In11.Cu" signal "L12")
		(26 "In12.Cu" signal "L13GND")
		(2 "B.Cu" signal "BOTTOM")
		(9 "F.Adhes" user "F.Adhesive")
		(11 "B.Adhes" user "B.Adhesive")
		(13 "F.Paste" user "Package Geometry/Pastemask Top")
		(15 "B.Paste" user "Package Geometry/Pastemask Bottom")
		(5 "F.SilkS" user "Ref Des/Silkscreen Top")
		(7 "B.SilkS" user "Ref Des/Silkscreen Bottom")
		(1 "F.Mask" user "Board Geometry/Soldermask Top")
		(3 "B.Mask" user "Board Geometry/Soldermask Bottom")
		(17 "Dwgs.User" user "User.Drawings")
		(19 "Cmts.User" user "User.Comments")
		(21 "Eco1.User" user "User.Eco1")
		(23 "Eco2.User" user "User.Eco2")
		(25 "Edge.Cuts" user "Board Geometry/Outline")
		(27 "Margin" user)
		(31 "F.CrtYd" user "Package Geometry/Place Bound Top")
		(29 "B.CrtYd" user "Package Geometry/Place Bound Bottom")
		(35 "F.Fab" user "Ref Des/Assembly Top")
		(33 "B.Fab" user "Ref Des/Assembly Bottom")
	)
	(footprint ""
		(layer "B.Cu")
		(at 409.6004 -146.939 -90)
		(property "Reference" "C2L24"
			(at 0 0 90)
			(layer "B.SilkS")
			(hide yes)
			(effects
				(font
					(size 1.27 1.27)
				)
				(justify mirror)
			)
		)
		(property "Value" ""
			(at 0 0 90)
			(layer "B.Fab")
			(effects
				(font
					(size 1.27 1.27)
				)
				(justify mirror)
			)
		)
		(duplicate_pad_numbers_are_jumpers no)
		(fp_poly
			(pts
				(xy -0.3048 -0.1016) (xy -0.3048 0.9906) (xy 0.3048 0.9906) (xy 0.3048 -0.1016)
			)
			(stroke
				(width 0)
				(type default)
			)
			(fill no)
			(layer "B.CrtYd")
		)
		(fp_line
			(start -0.3048 0.9906)
			(end -0.3048 -0.1016)
			(stroke
				(width 0.1)
				(type default)
			)
			(layer "B.Fab")
		)
		(fp_line
			(start 0.3048 0.9906)
			(end -0.3048 0.9906)
			(stroke
				(width 0.1)
				(type default)
			)
			(layer "B.Fab")
		)
		(fp_line
			(start -0.3048 -0.1016)
			(end 0.3048 -0.1016)
			(stroke
				(width 0.1)
				(type default)
			)
			(layer "B.Fab")
		)
		(fp_line
			(start 0.3048 -0.1016)
			(end 0.3048 0.9906)
			(stroke
				(width 0.1)
				(type default)
			)
			(layer "B.Fab")
		)
		(pad "1" smd rect
			(at 0 0 90)
			(size 0.508 0.508)
			(layers "B.Cu" "B.Mask" "B.Paste")
			(net "SATA6G_P7_TX_C_DP")
		)
		(pad "2" smd rect
			(at 0 0.889 90)
			(size 0.508 0.508)
			(layers "B.Cu" "B.Mask" "B.Paste")
			(net "SATA6G_PCH_PCIE_UP_SATA_TXP<7>")
		)
		(zone
			(layer "B.Cu")
			(hatch none 0.5)
			(connect_pads
				(clearance 0)
			)
			(min_thickness 0.25)
			(keepout
				(tracks not_allowed)
				(vias allowed)
				(pads allowed)
				(copperpour not_allowed)
				(footprints allowed)
			)
			(placement
				(enabled no)
				(sheetname "")
			)
			(fill
				(thermal_gap 0.5)
				(thermal_bridge_width 0.5)
				(island_removal_mode 0)
			)
			(polygon
				(pts
					(xy 408.9654 -146.685) (xy 408.9654 -147.193) (xy 409.3464 -147.193) (xy 409.3464 -146.685)
				)
			)
		)
		(zone
			(layer "B.Cu")
			(hatch none 0.5)
			(connect_pads
				(clearance 0)
			)
			(min_thickness 0.25)
			(keepout
				(tracks allowed)
				(vias not_allowed)
				(pads allowed)
				(copperpour not_allowed)
				(footprints allowed)
			)
			(placement
				(enabled no)
				(sheetname "")
			)
			(fill
				(thermal_gap 0.5)
				(thermal_bridge_width 0.5)
				(island_removal_mode 0)
			)
			(polygon
				(pts
					(xy 409.3464 -146.685) (xy 409.3464 -147.193) (xy 408.9654 -147.193) (xy 408.9654 -146.685)
				)
			)
		)
	)
	(footprint ""
		(layer "B.Cu")
		(at 462.026 -116.49202)
		(property "Reference" "C1M9"
			(at 0 0 0)
			(layer "B.SilkS")
			(hide yes)
			(effects
				(font
					(size 1.27 1.27)
				)
				(justify mirror)
			)
		)
		(property "Value" ""
			(at 0 0 0)
			(layer "B.Fab")
			(effects
				(font
					(size 1.27 1.27)
				)
				(justify mirror)
			)
		)
		(duplicate_pad_numbers_are_jumpers no)
		(fp_rect
			(start -0.3048 0.9906)
			(end 0.3048 -0.1016)
			(stroke
				(width 0)
				(type default)
			)
			(fill no)
			(layer "B.CrtYd")
		)
		(fp_line
			(start -0.3048 -0.1016)
			(end 0.3048 -0.1016)
			(stroke
				(width 0.1)
				(type default)
			)
			(layer "B.Fab")
		)
		(fp_line
			(start -0.3048 0.9906)
			(end -0.3048 -0.1016)
			(stroke
				(width 0.1)
				(type default)
			)
			(layer "B.Fab")
		)
		(fp_line
			(start 0.3048 -0.1016)
			(end 0.3048 0.9906)
			(stroke
				(width 0.1)
				(type default)
			)
			(layer "B.Fab")
		)
		(fp_line
			(start 0.3048 0.9906)
			(end -0.3048 0.9906)
			(stroke
				(width 0.1)
				(type default)
			)
			(layer "B.Fab")
		)
		(pad "1" smd rect
			(at 0 0 180)
			(size 0.508 0.508)
			(layers "B.Cu" "B.Mask" "B.Paste")
			(net "P3E_CPU0_PE3_OCP_TXN<14>")
		)
		(pad "2" smd rect
			(at 0 0.889 180)
			(size 0.508 0.508)
			(layers "B.Cu" "B.Mask" "B.Paste")
			(net "P3E_OCP_CPU0_PE3_C_TXN<14>")
		)
		(zone
			(layer "B.Cu")
			(hatch none 0.5)
			(connect_pads
				(clearance 0)
			)
			(min_thickness 0.25)
			(keepout
				(tracks allowed)
				(vias not_allowed)
				(pads allowed)
				(copperpour not_allowed)
				(footprints allowed)
			)
			(placement
				(enabled no)
				(sheetname "")
			)
			(fill
				(thermal_gap 0.5)
				(thermal_bridge_width 0.5)
				(island_removal_mode 0)
			)
			(polygon
				(pts
					(xy 461.772 -115.85702) (xy 462.28 -115.85702) (xy 462.28 -116.23802) (xy 461.772 -116.23802)
				)
			)
		)
	)
	(footprint ""
		(layer "B.Cu")
		(at 399.764758 -115.605814)
		(property "Reference" "R24W1"
			(at 0.8382 -0.67818 0)
			(unlocked yes)
			(layer "B.SilkS")
			(effects
				(font
					(size 0.4064 0.254)
					(thickness 0.1524)
				)
				(justify left mirror)
			)
		)
		(property "Value" ""
			(at 0 0 0)
			(layer "B.Fab")
			(effects
				(font
					(size 1.27 1.27)
				)
				(justify mirror)
			)
		)
		(duplicate_pad_numbers_are_jumpers no)
		(fp_poly
			(pts
				(xy 0.2794 -0.1016) (xy -0.2794 -0.1016) (xy -0.2794 0.9906) (xy 0.2794 0.9906)
			)
			(stroke
				(width 0)
				(type default)
			)
			(fill no)
			(layer "B.CrtYd")
		)
		(fp_line
			(start -0.2794 -0.1016)
			(end 0.2794 -0.1016)
			(stroke
				(width 0.1)
				(type default)
			)
			(layer "B.Fab")
		)
		(fp_line
			(start -0.2794 0.9906)
			(end -0.2794 -0.1016)
			(stroke
				(width 0.1)
				(type default)
			)
			(layer "B.Fab")
		)
		(fp_line
			(start 0.2794 -0.1016)
			(end 0.2794 0.9906)
			(stroke
				(width 0.1)
				(type default)
			)
			(layer "B.Fab")
		)
		(fp_line
			(start 0.2794 0.9906)
			(end -0.2794 0.9906)
			(stroke
				(width 0.1)
				(type default)
			)
			(layer "B.Fab")
		)
		(pad "1" smd rect
			(at 0 0 180)
			(size 0.508 0.508)
			(layers "B.Cu" "B.Mask" "B.Paste")
			(net "P3V3_STBY")
		)
		(pad "2" smd rect
			(at 0 0.889 180)
			(size 0.508 0.508)
			(layers "B.Cu" "B.Mask" "B.Paste")
			(net "SMB_SLOTX24_PCH_STBY_LVC3_SDA")
		)
		(zone
			(layer "B.Cu")
			(hatch none 0.5)
			(connect_pads
				(clearance 0)
			)
			(min_thickness 0.25)
			(keepout
				(tracks allowed)
				(vias not_allowed)
				(pads allowed)
				(copperpour not_allowed)
				(footprints allowed)
			)
			(placement
				(enabled no)
				(sheetname "")
			)
			(fill
				(thermal_gap 0.5)
				(thermal_bridge_width 0.5)
				(island_removal_mode 0)
			)
			(polygon
				(pts
					(xy 400.018758 -115.351814) (xy 399.510758 -115.351814) (xy 399.510758 -114.970814) (xy 400.018758 -114.970814)
				)
			)
		)
		(zone
			(layer "B.Cu")
			(hatch none 0.5)
			(connect_pads
				(clearance 0)
			)
			(min_thickness 0.25)
			(keepout
				(tracks not_allowed)
				(vias allowed)
				(pads allowed)
				(copperpour not_allowed)
				(footprints allowed)
			)
			(placement
				(enabled no)
				(sheetname "")
			)
			(fill
				(thermal_gap 0.5)
				(thermal_bridge_width 0.5)
				(island_removal_mode 0)
			)
			(polygon
				(pts
					(xy 400.018758 -114.970814) (xy 399.510758 -114.970814) (xy 399.510758 -115.351814) (xy 400.018758 -115.351814)
				)
			)
		)
	)
	(footprint ""
		(layer "B.Cu")
		(at 413.059118 -92.428314)
		(property "Reference" "R3R4"
			(at 0 0 0)
			(layer "B.SilkS")
			(hide yes)
			(effects
				(font
					(size 1.27 1.27)
				)
				(justify mirror)
			)
		)
		(property "Value" ""
			(at 0 0 0)
			(layer "B.Fab")
			(effects
				(font
					(size 1.27 1.27)
				)
				(justify mirror)
			)
		)
		(duplicate_pad_numbers_are_jumpers no)
		(fp_poly
			(pts
				(xy 0.2794 -0.1016) (xy -0.2794 -0.1016) (xy -0.2794 0.9906) (xy 0.2794 0.9906)
			)
			(stroke
				(width 0)
				(type default)
			)
			(fill no)
			(layer "B.CrtYd")
		)
		(fp_line
			(start -0.2794 -0.1016)
			(end 0.2794 -0.1016)
			(stroke
				(width 0.1)
				(type default)
			)
			(layer "B.Fab")
		)
		(fp_line
			(start -0.2794 0.9906)
			(end -0.2794 -0.1016)
			(stroke
				(width 0.1)
				(type default)
			)
			(layer "B.Fab")
		)
		(fp_line
			(start 0.2794 -0.1016)
			(end 0.2794 0.9906)
			(stroke
				(width 0.1)
				(type default)
			)
			(layer "B.Fab")
		)
		(fp_line
			(start 0.2794 0.9906)
			(end -0.2794 0.9906)
			(stroke
				(width 0.1)
				(type default)
			)
			(layer "B.Fab")
		)
		(pad "1" smd rect
			(at 0 0 180)
			(size 0.508 0.508)
			(layers "B.Cu" "B.Mask" "B.Paste")
			(net "P3V3")
		)
		(pad "2" smd rect
			(at 0 0.889 180)
			(size 0.508 0.508)
			(layers "B.Cu" "B.Mask" "B.Paste")
			(net "H_CPU0_MEMDEF_MEMHOT")
		)
		(zone
			(layer "B.Cu")
			(hatch none 0.5)
			(connect_pads
				(clearance 0)
			)
			(min_thickness 0.25)
			(keepout
				(tracks allowed)
				(vias not_allowed)
				(pads allowed)
				(copperpour not_allowed)
				(footprints allowed)
			)
			(placement
				(enabled no)
				(sheetname "")
			)
			(fill
				(thermal_gap 0.5)
				(thermal_bridge_width 0.5)
				(island_removal_mode 0)
			)
			(polygon
				(pts
					(xy 413.313118 -92.174314) (xy 412.805118 -92.174314) (xy 412.805118 -91.793314) (xy 413.313118 -91.793314)
				)
			)
		)
		(zone
			(layer "B.Cu")
			(hatch none 0.5)
			(connect_pads
				(clearance 0)
			)
			(min_thickness 0.25)
			(keepout
				(tracks not_allowed)
				(vias allowed)
				(pads allowed)
				(copperpour not_allowed)
				(footprints allowed)
			)
			(placement
				(enabled no)
				(sheetname "")
			)
			(fill
				(thermal_gap 0.5)
				(thermal_bridge_width 0.5)
				(island_removal_mode 0)
			)
			(polygon
				(pts
					(xy 413.313118 -91.793314) (xy 412.805118 -91.793314) (xy 412.805118 -92.174314) (xy 413.313118 -92.174314)
				)
			)
		)
	)
	(footprint ""
		(layer "B.Cu")
		(at 386.80898 -126.9238 180)
		(property "Reference" "R3M10"
			(at 0 0 0)
			(layer "B.SilkS")
			(hide yes)
			(effects
				(font
					(size 1.27 1.27)
				)
				(justify mirror)
			)
		)
		(property "Value" ""
			(at 0 0 0)
			(layer "B.Fab")
			(effects
				(font
					(size 1.27 1.27)
				)
				(justify mirror)
			)
		)
		(duplicate_pad_numbers_are_jumpers no)
		(fp_poly
			(pts
				(xy 0.2794 -0.1016) (xy -0.2794 -0.1016) (xy -0.2794 0.9906) (xy 0.2794 0.9906)
			)
			(stroke
				(width 0)
				(type default)
			)
			(fill no)
			(layer "B.CrtYd")
		)
		(fp_line
			(start 0.2794 0.9906)
			(end -0.2794 0.9906)
			(stroke
				(width 0.1)
				(type default)
			)
			(layer "B.Fab")
		)
		(fp_line
			(start 0.2794 -0.1016)
			(end 0.2794 0.9906)
			(stroke
				(width 0.1)
				(type default)
			)
			(layer "B.Fab")
		)
		(fp_line
			(start -0.2794 0.9906)
			(end -0.2794 -0.1016)
			(stroke
				(width 0.1)
				(type default)
			)
			(layer "B.Fab")
		)
		(fp_line
			(start -0.2794 -0.1016)
			(end 0.2794 -0.1016)
			(stroke
				(width 0.1)
				(type default)
			)
			(layer "B.Fab")
		)
		(pad "1" smd rect
			(at 0 0)
			(size 0.508 0.508)
			(layers "B.Cu" "B.Mask" "B.Paste")
			(net "XDP_PCH_CPU_TCK0")
		)
		(pad "2" smd rect
			(at 0 0.889)
			(size 0.508 0.508)
			(layers "B.Cu" "B.Mask" "B.Paste")
			(net "GND")
		)
		(zone
			(layer "B.Cu")
			(hatch none 0.5)
			(connect_pads
				(clearance 0)
			)
			(min_thickness 0.25)
			(keepout
				(tracks not_allowed)
				(vias allowed)
				(pads allowed)
				(copperpour not_allowed)
				(footprints allowed)
			)
			(placement
				(enabled no)
				(sheetname "")
			)
			(fill
				(thermal_gap 0.5)
				(thermal_bridge_width 0.5)
				(island_removal_mode 0)
			)
			(polygon
				(pts
					(xy 386.55498 -127.5588) (xy 387.06298 -127.5588) (xy 387.06298 -127.1778) (xy 386.55498 -127.1778)
				)
			)
		)
		(zone
			(layer "B.Cu")
			(hatch none 0.5)
			(connect_pads
				(clearance 0)
			)
			(min_thickness 0.25)
			(keepout
				(tracks allowed)
				(vias not_allowed)
				(pads allowed)
				(copperpour not_allowed)
				(footprints allowed)
			)
			(placement
				(enabled no)
				(sheetname "")
			)
			(fill
				(thermal_gap 0.5)
				(thermal_bridge_width 0.5)
				(island_removal_mode 0)
			)
			(polygon
				(pts
					(xy 386.55498 -127.1778) (xy 387.06298 -127.1778) (xy 387.06298 -127.5588) (xy 386.55498 -127.5588)
				)
			)
		)
	)
	(footprint ""
		(layer "B.Cu")
		(at 162.179 -69.596)
		(property "Reference" "R7P20"
			(at 0 0 0)
			(layer "B.SilkS")
			(hide yes)
			(effects
				(font
					(size 1.27 1.27)
				)
				(justify mirror)
			)
		)
		(property "Value" ""
			(at 0 0 0)
			(layer "B.Fab")
			(effects
				(font
					(size 1.27 1.27)
				)
				(justify mirror)
			)
		)
		(duplicate_pad_numbers_are_jumpers no)
		(fp_poly
			(pts
				(xy 0.2794 -0.1016) (xy -0.2794 -0.1016) (xy -0.2794 0.9906) (xy 0.2794 0.9906)
			)
			(stroke
				(width 0)
				(type default)
			)
			(fill no)
			(layer "B.CrtYd")
		)
		(fp_line
			(start -0.2794 -0.1016)
			(end 0.2794 -0.1016)
			(stroke
				(width 0.1)
				(type default)
			)
			(layer "B.Fab")
		)
		(fp_line
			(start -0.2794 0.9906)
			(end -0.2794 -0.1016)
			(stroke
				(width 0.1)
				(type default)
			)
			(layer "B.Fab")
		)
		(fp_line
			(start 0.2794 -0.1016)
			(end 0.2794 0.9906)
			(stroke
				(width 0.1)
				(type default)
			)
			(layer "B.Fab")
		)
		(fp_line
			(start 0.2794 0.9906)
			(end -0.2794 0.9906)
			(stroke
				(width 0.1)
				(type default)
			)
			(layer "B.Fab")
		)
		(pad "1" smd rect
			(at 0 0 180)
			(size 0.508 0.508)
			(layers "B.Cu" "B.Mask" "B.Paste")
			(net "PVCCIO_CPU0")
		)
		(pad "2" smd rect
			(at 0 0.889 180)
			(size 0.508 0.508)
			(layers "B.Cu" "B.Mask" "B.Paste")
			(net "H_CPU1_FAST_WAKE_N")
		)
		(zone
			(layer "B.Cu")
			(hatch none 0.5)
			(connect_pads
				(clearance 0)
			)
			(min_thickness 0.25)
			(keepout
				(tracks allowed)
				(vias not_allowed)
				(pads allowed)
				(copperpour not_allowed)
				(footprints allowed)
			)
			(placement
				(enabled no)
				(sheetname "")
			)
			(fill
				(thermal_gap 0.5)
				(thermal_bridge_width 0.5)
				(island_removal_mode 0)
			)
			(polygon
				(pts
					(xy 162.433 -69.342) (xy 161.925 -69.342) (xy 161.925 -68.961) (xy 162.433 -68.961)
				)
			)
		)
		(zone
			(layer "B.Cu")
			(hatch none 0.5)
			(connect_pads
				(clearance 0)
			)
			(min_thickness 0.25)
			(keepout
				(tracks not_allowed)
				(vias allowed)
				(pads allowed)
				(copperpour not_allowed)
				(footprints allowed)
			)
			(placement
				(enabled no)
				(sheetname "")
			)
			(fill
				(thermal_gap 0.5)
				(thermal_bridge_width 0.5)
				(island_removal_mode 0)
			)
			(polygon
				(pts
					(xy 162.433 -68.961) (xy 161.925 -68.961) (xy 161.925 -69.342) (xy 162.433 -69.342)
				)
			)
		)
	)
)
